(kicad_pcb
	(version 20260206)
	(generator "pcbnew")
	(generator_version "10.0")
	(general
		(thickness 1.6)
		(legacy_teardrops no)
	)
	(paper "A4")
	(title_block
		(title "03242023_DA0F0TMBIJ0_F0T_Motherboard_J_brd_V01_OCP.brd")
		(comment 1 "Grand Teton / footprints 5619-5626 of 6105")
	)
	(layers
		(0 "F.Cu" signal "TOP")
		(4 "In1.Cu" signal "GND")
		(6 "In2.Cu" signal "IN1")
		(8 "In3.Cu" signal "GND1")
		(10 "In4.Cu" signal "IN2")
		(12 "In5.Cu" signal "GND2")
		(14 "In6.Cu" signal "IN3")
		(16 "In7.Cu" signal "GND3")
		(18 "In8.Cu" signal "VCC")
		(20 "In9.Cu" signal "VCC1")
		(22 "In10.Cu" signal "GND4")
		(24 "In11.Cu" signal "IN4")
		(26 "In12.Cu" signal "GND5")
		(28 "In13.Cu" signal "IN5")
		(30 "In14.Cu" signal "GND6")
		(32 "In15.Cu" signal "IN6")
		(34 "In16.Cu" signal "GND7")
		(2 "B.Cu" signal "BOTTOM")
		(9 "F.Adhes" user "F.Adhesive")
		(11 "B.Adhes" user "B.Adhesive")
		(13 "F.Paste" user "Package Geometry/Pastemask Top")
		(15 "B.Paste" user "Package Geometry/Pastemask Bottom")
		(5 "F.SilkS" user "Ref Des/Silkscreen Top")
		(7 "B.SilkS" user "Ref Des/Silkscreen Bottom")
		(1 "F.Mask" user "Board Geometry/Soldermask Top")
		(3 "B.Mask" user "Board Geometry/Soldermask Bottom")
		(17 "Dwgs.User" user "User.Drawings")
		(19 "Cmts.User" user "User.Comments")
		(21 "Eco1.User" user "User.Eco1")
		(23 "Eco2.User" user "User.Eco2")
		(25 "Edge.Cuts" user "Board Geometry/Outline")
		(27 "Margin" user)
		(31 "F.CrtYd" user "Package Geometry/Place Bound Top")
		(29 "B.CrtYd" user "Package Geometry/Place Bound Bottom")
		(35 "F.Fab" user "Ref Des/Assembly Top")
		(33 "B.Fab" user "Ref Des/Assembly Bottom")
	)
	(footprint ""
		(layer "B.Cu")
		(at 157.504638 -13.762228 90)
		(property "Reference" "R2413"
			(at 0 0 90)
			(layer "B.SilkS")
			(hide yes)
			(effects
				(font
					(size 1.27 1.27)
				)
				(justify mirror)
			)
		)
		(property "Value" ""
			(at 0 0 90)
			(layer "B.Fab")
			(effects
				(font
					(size 1.27 1.27)
				)
				(justify mirror)
			)
		)
		(duplicate_pad_numbers_are_jumpers no)
		(fp_line
			(start 0.7874 -0.4064)
			(end -0.7874 -0.4064)
			(stroke
				(width 0.1524)
				(type default)
			)
			(layer "B.SilkS")
		)
		(fp_line
			(start -0.7874 -0.4064)
			(end -0.7874 0.4064)
			(stroke
				(width 0.1524)
				(type default)
			)
			(layer "B.SilkS")
		)
		(fp_line
			(start 0.7874 0.4064)
			(end 0.7874 -0.4064)
			(stroke
				(width 0.1524)
				(type default)
			)
			(layer "B.SilkS")
		)
		(fp_line
			(start -0.7874 0.4064)
			(end 0.7874 0.4064)
			(stroke
				(width 0.1524)
				(type default)
			)
			(layer "B.SilkS")
		)
		(fp_line
			(start 0.67945 -0.305054)
			(end 0.12065 -0.305054)
			(stroke
				(width 0.1)
				(type default)
			)
			(layer "B.Fab")
		)
		(fp_line
			(start 0.12065 -0.305054)
			(end 0.12065 -0.2794)
			(stroke
				(width 0.1)
				(type default)
			)
			(layer "B.Fab")
		)
		(fp_line
			(start -0.12065 -0.3048)
			(end -0.67945 -0.3048)
			(stroke
				(width 0.1)
				(type default)
			)
			(layer "B.Fab")
		)
		(fp_line
			(start -0.67945 -0.3048)
			(end -0.67945 0.3048)
			(stroke
				(width 0.1)
				(type default)
			)
			(layer "B.Fab")
		)
		(fp_line
			(start 0.12065 -0.2794)
			(end -0.12065 -0.2794)
			(stroke
				(width 0.1)
				(type default)
			)
			(layer "B.Fab")
		)
		(fp_line
			(start -0.12065 -0.2794)
			(end -0.12065 -0.3048)
			(stroke
				(width 0.1)
				(type default)
			)
			(layer "B.Fab")
		)
		(fp_line
			(start 0.12065 0.2794)
			(end 0.12065 0.3048)
			(stroke
				(width 0.1)
				(type default)
			)
			(layer "B.Fab")
		)
		(fp_line
			(start -0.120396 0.2794)
			(end 0.12065 0.2794)
			(stroke
				(width 0.1)
				(type default)
			)
			(layer "B.Fab")
		)
		(fp_line
			(start 0.67945 0.3048)
			(end 0.67945 -0.305054)
			(stroke
				(width 0.1)
				(type default)
			)
			(layer "B.Fab")
		)
		(fp_line
			(start 0.12065 0.3048)
			(end 0.67945 0.3048)
			(stroke
				(width 0.1)
				(type default)
			)
			(layer "B.Fab")
		)
		(fp_line
			(start -0.120396 0.3048)
			(end -0.120396 0.2794)
			(stroke
				(width 0.1)
				(type default)
			)
			(layer "B.Fab")
		)
		(fp_line
			(start -0.67945 0.3048)
			(end -0.120396 0.3048)
			(stroke
				(width 0.1)
				(type default)
			)
			(layer "B.Fab")
		)
		(pad "1" smd circle
			(at 0.40005 0 270)
			(size 0 0)
			(layers "B.Cu" "B.Mask" "B.Paste")
			(net "SMB_2_BMC_GPU_SCL")
		)
		(pad "2" smd circle
			(at -0.40005 0 270)
			(size 0 0)
			(layers "B.Cu" "B.Mask" "B.Paste")
			(net "SMB_PCIE2_3V3AUX_SCL_R0")
		)
	)
	(footprint ""
		(layer "B.Cu")
		(at 79.836772 -331.596492 -90)
		(property "Reference" "PC498_P1_7"
			(at 0 0 90)
			(layer "B.SilkS")
			(hide yes)
			(effects
				(font
					(size 1.27 1.27)
				)
				(justify mirror)
			)
		)
		(property "Value" ""
			(at 0 0 90)
			(layer "B.Fab")
			(effects
				(font
					(size 1.27 1.27)
				)
				(justify mirror)
			)
		)
		(duplicate_pad_numbers_are_jumpers no)
		(fp_line
			(start -1.524 0.762)
			(end 1.524 0.762)
			(stroke
				(width 0.1524)
				(type default)
			)
			(layer "B.SilkS")
		)
		(fp_line
			(start 1.524 0.762)
			(end 1.524 -0.762)
			(stroke
				(width 0.1524)
				(type default)
			)
			(layer "B.SilkS")
		)
		(fp_line
			(start -1.524 -0.762)
			(end -1.524 0.762)
			(stroke
				(width 0.1524)
				(type default)
			)
			(layer "B.SilkS")
		)
		(fp_line
			(start 1.524 -0.762)
			(end -1.524 -0.762)
			(stroke
				(width 0.1524)
				(type default)
			)
			(layer "B.SilkS")
		)
		(fp_line
			(start -1.1049 0.724916)
			(end -1.1049 -0.724916)
			(stroke
				(width 0.1)
				(type default)
			)
			(layer "B.Fab")
		)
		(fp_line
			(start 1.1049 0.724916)
			(end -1.1049 0.724916)
			(stroke
				(width 0.1)
				(type default)
			)
			(layer "B.Fab")
		)
		(fp_line
			(start -1.1049 -0.724916)
			(end 1.1049 -0.724916)
			(stroke
				(width 0.1)
				(type default)
			)
			(layer "B.Fab")
		)
		(fp_line
			(start 1.1049 -0.724916)
			(end 1.1049 0.724916)
			(stroke
				(width 0.1)
				(type default)
			)
			(layer "B.Fab")
		)
		(pad "1" smd rect
			(at 0.889 0 270)
			(size 1.016 1.27)
			(layers "B.Cu" "B.Mask" "B.Paste")
			(net "PVCCIN_CPU1")
		)
		(pad "2" smd rect
			(at -0.889 0 270)
			(size 1.016 1.27)
			(layers "B.Cu" "B.Mask" "B.Paste")
			(net "GND")
		)
	)
	(footprint ""
		(layer "B.Cu")
		(at 391.408158 -336.43697)
		(property "Reference" "C1436"
			(at 0 0 0)
			(layer "B.SilkS")
			(hide yes)
			(effects
				(font
					(size 1.27 1.27)
				)
				(justify mirror)
			)
		)
		(property "Value" ""
			(at 0 0 0)
			(layer "B.Fab")
			(effects
				(font
					(size 1.27 1.27)
				)
				(justify mirror)
			)
		)
		(duplicate_pad_numbers_are_jumpers no)
		(fp_line
			(start -0.299974 -0.150114)
			(end -0.299974 0.150114)
			(stroke
				(width 0.1)
				(type default)
			)
			(layer "B.Fab")
		)
		(fp_line
			(start -0.299974 0.150114)
			(end 0.299974 0.150114)
			(stroke
				(width 0.1)
				(type default)
			)
			(layer "B.Fab")
		)
		(fp_line
			(start 0.299974 -0.150114)
			(end -0.299974 -0.150114)
			(stroke
				(width 0.1)
				(type default)
			)
			(layer "B.Fab")
		)
		(fp_line
			(start 0.299974 0.150114)
			(end 0.299974 -0.150114)
			(stroke
				(width 0.1)
				(type default)
			)
			(layer "B.Fab")
		)
		(pad "1" smd rect
			(at 0.2667 0 180)
			(size 0.3048 0.381)
			(layers "B.Cu" "B.Mask" "B.Paste")
			(net "PVPP_HBM_CPU0")
		)
		(pad "2" smd rect
			(at -0.2667 0 180)
			(size 0.3048 0.381)
			(layers "B.Cu" "B.Mask" "B.Paste")
			(net "GND")
		)
	)
	(footprint ""
		(layer "B.Cu")
		(at 349.675704 -65.09512)
		(property "Reference" "C155"
			(at 0 0 0)
			(layer "B.SilkS")
			(hide yes)
			(effects
				(font
					(size 1.27 1.27)
				)
				(justify mirror)
			)
		)
		(property "Value" ""
			(at 0 0 0)
			(layer "B.Fab")
			(effects
				(font
					(size 1.27 1.27)
				)
				(justify mirror)
			)
		)
		(duplicate_pad_numbers_are_jumpers no)
		(fp_line
			(start -0.299974 -0.150114)
			(end -0.299974 0.150114)
			(stroke
				(width 0.1)
				(type default)
			)
			(layer "B.Fab")
		)
		(fp_line
			(start -0.299974 0.150114)
			(end 0.299974 0.150114)
			(stroke
				(width 0.1)
				(type default)
			)
			(layer "B.Fab")
		)
		(fp_line
			(start 0.299974 -0.150114)
			(end -0.299974 -0.150114)
			(stroke
				(width 0.1)
				(type default)
			)
			(layer "B.Fab")
		)
		(fp_line
			(start 0.299974 0.150114)
			(end 0.299974 -0.150114)
			(stroke
				(width 0.1)
				(type default)
			)
			(layer "B.Fab")
		)
		(pad "1" smd rect
			(at 0.2667 0 180)
			(size 0.3048 0.381)
			(layers "B.Cu" "B.Mask" "B.Paste")
			(net "DMI_CPU0_PCH_RX_C_DN<7>")
		)
		(pad "2" smd rect
			(at -0.2667 0 180)
			(size 0.3048 0.381)
			(layers "B.Cu" "B.Mask" "B.Paste")
			(net "DMI_CPU0_PCH_RX_DN<7>")
		)
	)
	(footprint ""
		(layer "B.Cu")
		(at 83.478624 -184.096152 -90)
		(property "Reference" "R61"
			(at 0 0 90)
			(layer "B.SilkS")
			(hide yes)
			(effects
				(font
					(size 1.27 1.27)
				)
				(justify mirror)
			)
		)
		(property "Value" ""
			(at 0 0 90)
			(layer "B.Fab")
			(effects
				(font
					(size 1.27 1.27)
				)
				(justify mirror)
			)
		)
		(duplicate_pad_numbers_are_jumpers no)
		(fp_line
			(start -0.7874 0.4064)
			(end 0.7874 0.4064)
			(stroke
				(width 0.1524)
				(type default)
			)
			(layer "B.SilkS")
		)
		(fp_line
			(start 0.7874 0.4064)
			(end 0.7874 -0.4064)
			(stroke
				(width 0.1524)
				(type default)
			)
			(layer "B.SilkS")
		)
		(fp_line
			(start -0.7874 -0.4064)
			(end -0.7874 0.4064)
			(stroke
				(width 0.1524)
				(type default)
			)
			(layer "B.SilkS")
		)
		(fp_line
			(start 0.7874 -0.4064)
			(end -0.7874 -0.4064)
			(stroke
				(width 0.1524)
				(type default)
			)
			(layer "B.SilkS")
		)
		(fp_line
			(start -0.67945 0.3048)
			(end -0.120396 0.3048)
			(stroke
				(width 0.1)
				(type default)
			)
			(layer "B.Fab")
		)
		(fp_line
			(start -0.120396 0.3048)
			(end -0.120396 0.2794)
			(stroke
				(width 0.1)
				(type default)
			)
			(layer "B.Fab")
		)
		(fp_line
			(start 0.12065 0.3048)
			(end 0.67945 0.3048)
			(stroke
				(width 0.1)
				(type default)
			)
			(layer "B.Fab")
		)
		(fp_line
			(start 0.67945 0.3048)
			(end 0.67945 -0.305054)
			(stroke
				(width 0.1)
				(type default)
			)
			(layer "B.Fab")
		)
		(fp_line
			(start -0.120396 0.2794)
			(end 0.12065 0.2794)
			(stroke
				(width 0.1)
				(type default)
			)
			(layer "B.Fab")
		)
		(fp_line
			(start 0.12065 0.2794)
			(end 0.12065 0.3048)
			(stroke
				(width 0.1)
				(type default)
			)
			(layer "B.Fab")
		)
		(fp_line
			(start -0.12065 -0.2794)
			(end -0.12065 -0.3048)
			(stroke
				(width 0.1)
				(type default)
			)
			(layer "B.Fab")
		)
		(fp_line
			(start 0.12065 -0.2794)
			(end -0.12065 -0.2794)
			(stroke
				(width 0.1)
				(type default)
			)
			(layer "B.Fab")
		)
		(fp_line
			(start -0.67945 -0.3048)
			(end -0.67945 0.3048)
			(stroke
				(width 0.1)
				(type default)
			)
			(layer "B.Fab")
		)
		(fp_line
			(start -0.12065 -0.3048)
			(end -0.67945 -0.3048)
			(stroke
				(width 0.1)
				(type default)
			)
			(layer "B.Fab")
		)
		(fp_line
			(start 0.12065 -0.305054)
			(end 0.12065 -0.2794)
			(stroke
				(width 0.1)
				(type default)
			)
			(layer "B.Fab")
		)
		(fp_line
			(start 0.67945 -0.305054)
			(end 0.12065 -0.305054)
			(stroke
				(width 0.1)
				(type default)
			)
			(layer "B.Fab")
		)
		(pad "1" smd circle
			(at 0.40005 0 90)
			(size 0 0)
			(layers "B.Cu" "B.Mask" "B.Paste")
			(net "H_CPU_PRDY_QS_GTL_N")
		)
		(pad "2" smd circle
			(at -0.40005 0 90)
			(size 0 0)
			(layers "B.Cu" "B.Mask" "B.Paste")
			(net "H_CPU1_PRDY_QS_GTL_R_N")
		)
	)
	(footprint ""
		(layer "B.Cu")
		(at 179.87645 -408.256994 90)
		(property "Reference" "R4696"
			(at 0 0 90)
			(layer "B.SilkS")
			(hide yes)
			(effects
				(font
					(size 1.27 1.27)
				)
				(justify mirror)
			)
		)
		(property "Value" ""
			(at 0 0 90)
			(layer "B.Fab")
			(effects
				(font
					(size 1.27 1.27)
				)
				(justify mirror)
			)
		)
		(duplicate_pad_numbers_are_jumpers no)
		(fp_line
			(start 0.7874 -0.4064)
			(end -0.7874 -0.4064)
			(stroke
				(width 0.1524)
				(type default)
			)
			(layer "B.SilkS")
		)
		(fp_line
			(start -0.7874 -0.4064)
			(end -0.7874 0.4064)
			(stroke
				(width 0.1524)
				(type default)
			)
			(layer "B.SilkS")
		)
		(fp_line
			(start 0.7874 0.4064)
			(end 0.7874 -0.4064)
			(stroke
				(width 0.1524)
				(type default)
			)
			(layer "B.SilkS")
		)
		(fp_line
			(start -0.7874 0.4064)
			(end 0.7874 0.4064)
			(stroke
				(width 0.1524)
				(type default)
			)
			(layer "B.SilkS")
		)
		(fp_line
			(start 0.67945 -0.305054)
			(end 0.12065 -0.305054)
			(stroke
				(width 0.1)
				(type default)
			)
			(layer "B.Fab")
		)
		(fp_line
			(start 0.12065 -0.305054)
			(end 0.12065 -0.2794)
			(stroke
				(width 0.1)
				(type default)
			)
			(layer "B.Fab")
		)
		(fp_line
			(start -0.12065 -0.3048)
			(end -0.67945 -0.3048)
			(stroke
				(width 0.1)
				(type default)
			)
			(layer "B.Fab")
		)
		(fp_line
			(start -0.67945 -0.3048)
			(end -0.67945 0.3048)
			(stroke
				(width 0.1)
				(type default)
			)
			(layer "B.Fab")
		)
		(fp_line
			(start 0.12065 -0.2794)
			(end -0.12065 -0.2794)
			(stroke
				(width 0.1)
				(type default)
			)
			(layer "B.Fab")
		)
		(fp_line
			(start -0.12065 -0.2794)
			(end -0.12065 -0.3048)
			(stroke
				(width 0.1)
				(type default)
			)
			(layer "B.Fab")
		)
		(fp_line
			(start 0.12065 0.2794)
			(end 0.12065 0.3048)
			(stroke
				(width 0.1)
				(type default)
			)
			(layer "B.Fab")
		)
		(fp_line
			(start -0.120396 0.2794)
			(end 0.12065 0.2794)
			(stroke
				(width 0.1)
				(type default)
			)
			(layer "B.Fab")
		)
		(fp_line
			(start 0.67945 0.3048)
			(end 0.67945 -0.305054)
			(stroke
				(width 0.1)
				(type default)
			)
			(layer "B.Fab")
		)
		(fp_line
			(start 0.12065 0.3048)
			(end 0.67945 0.3048)
			(stroke
				(width 0.1)
				(type default)
			)
			(layer "B.Fab")
		)
		(fp_line
			(start -0.120396 0.3048)
			(end -0.120396 0.2794)
			(stroke
				(width 0.1)
				(type default)
			)
			(layer "B.Fab")
		)
		(fp_line
			(start -0.67945 0.3048)
			(end -0.120396 0.3048)
			(stroke
				(width 0.1)
				(type default)
			)
			(layer "B.Fab")
		)
		(pad "1" smd circle
			(at 0.40005 0 270)
			(size 0 0)
			(layers "B.Cu" "B.Mask" "B.Paste")
			(net "SMB_SML1_PMBUS_HSC_SDA")
		)
		(pad "2" smd circle
			(at -0.40005 0 270)
			(size 0 0)
			(layers "B.Cu" "B.Mask" "B.Paste")
			(net "SMB_SML1_PMBUS_HSC_MODULE_SDA")
		)
	)
	(footprint ""
		(layer "B.Cu")
		(at 456.092814 -321.549776 -90)
		(property "Reference" "C48"
			(at 0 0 90)
			(layer "B.SilkS")
			(hide yes)
			(effects
				(font
					(size 1.27 1.27)
				)
				(justify mirror)
			)
		)
		(property "Value" ""
			(at 0 0 90)
			(layer "B.Fab")
			(effects
				(font
					(size 1.27 1.27)
				)
				(justify mirror)
			)
		)
		(duplicate_pad_numbers_are_jumpers no)
		(fp_line
			(start -1.524 0.762)
			(end 1.524 0.762)
			(stroke
				(width 0.1524)
				(type default)
			)
			(layer "B.SilkS")
		)
		(fp_line
			(start 1.524 0.762)
			(end 1.524 -0.762)
			(stroke
				(width 0.1524)
				(type default)
			)
			(layer "B.SilkS")
		)
		(fp_line
			(start -1.524 -0.762)
			(end -1.524 0.762)
			(stroke
				(width 0.1524)
				(type default)
			)
			(layer "B.SilkS")
		)
		(fp_line
			(start 1.524 -0.762)
			(end -1.524 -0.762)
			(stroke
				(width 0.1524)
				(type default)
			)
			(layer "B.SilkS")
		)
		(fp_line
			(start -1.1049 0.724916)
			(end -1.1049 -0.724916)
			(stroke
				(width 0.1)
				(type default)
			)
			(layer "B.Fab")
		)
		(fp_line
			(start 1.1049 0.724916)
			(end -1.1049 0.724916)
			(stroke
				(width 0.1)
				(type default)
			)
			(layer "B.Fab")
		)
		(fp_line
			(start -1.1049 -0.724916)
			(end 1.1049 -0.724916)
			(stroke
				(width 0.1)
				(type default)
			)
			(layer "B.Fab")
		)
		(fp_line
			(start 1.1049 -0.724916)
			(end 1.1049 0.724916)
			(stroke
				(width 0.1)
				(type default)
			)
			(layer "B.Fab")
		)
		(pad "1" smd rect
			(at 0.889 0 270)
			(size 1.016 1.27)
			(layers "B.Cu" "B.Mask" "B.Paste")
			(net "P12V_S3_AUX_CPU0_NVDIMM")
		)
		(pad "2" smd rect
			(at -0.889 0 270)
			(size 1.016 1.27)
			(layers "B.Cu" "B.Mask" "B.Paste")
			(net "GND")
		)
	)
	(footprint ""
		(layer "B.Cu")
		(at 341.320628 -62.056264 90)
		(property "Reference" "C166"
			(at 0 0 90)
			(layer "B.SilkS")
			(hide yes)
			(effects
				(font
					(size 1.27 1.27)
				)
				(justify mirror)
			)
		)
		(property "Value" ""
			(at 0 0 90)
			(layer "B.Fab")
			(effects
				(font
					(size 1.27 1.27)
				)
				(justify mirror)
			)
		)
		(duplicate_pad_numbers_are_jumpers no)
		(fp_line
			(start 0.299974 -0.150114)
			(end -0.299974 -0.150114)
			(stroke
				(width 0.1)
				(type default)
			)
			(layer "B.Fab")
		)
		(fp_line
			(start -0.299974 -0.150114)
			(end -0.299974 0.150114)
			(stroke
				(width 0.1)
				(type default)
			)
			(layer "B.Fab")
		)
		(fp_line
			(start 0.299974 0.150114)
			(end 0.299974 -0.150114)
			(stroke
				(width 0.1)
				(type default)
			)
			(layer "B.Fab")
		)
		(fp_line
			(start -0.299974 0.150114)
			(end 0.299974 0.150114)
			(stroke
				(width 0.1)
				(type default)
			)
			(layer "B.Fab")
		)
		(pad "1" smd rect
			(at 0.2667 0 270)
			(size 0.3048 0.381)
			(layers "B.Cu" "B.Mask" "B.Paste")
			(net "DMI_CPU0_PCH_RX_C_DP<2>")
		)
		(pad "2" smd rect
			(at -0.2667 0 270)
			(size 0.3048 0.381)
			(layers "B.Cu" "B.Mask" "B.Paste")
			(net "DMI_CPU0_PCH_RX_DP<2>")
		)
	)
)
